(kicad_pcb
	(version 20260206)
	(generator "pcbnew")
	(generator_version "10.0")
	(general
		(thickness 1.6)
		(legacy_teardrops no)
	)
	(paper "A4")
	(title_block
		(title "04192023_DAF0TMB3IC0_F0TG_MB_C_brd_V02_OCP.brd")
		(comment 1 "Grand Teton / footprints 5645-5650 of 8354")
	)
	(layers
		(0 "F.Cu" signal "TOP")
		(4 "In1.Cu" signal "GND")
		(6 "In2.Cu" signal "IN1")
		(8 "In3.Cu" signal "GND1")
		(10 "In4.Cu" signal "IN2")
		(12 "In5.Cu" signal "GND2")
		(14 "In6.Cu" signal "IN3")
		(16 "In7.Cu" signal "GND3")
		(18 "In8.Cu" signal "VCC")
		(20 "In9.Cu" signal "VCC1")
		(22 "In10.Cu" signal "GND4")
		(24 "In11.Cu" signal "IN4")
		(26 "In12.Cu" signal "GND5")
		(28 "In13.Cu" signal "IN5")
		(30 "In14.Cu" signal "GND6")
		(32 "In15.Cu" signal "IN6")
		(34 "In16.Cu" signal "GND7")
		(2 "B.Cu" signal "BOTTOM")
		(9 "F.Adhes" user "F.Adhesive")
		(11 "B.Adhes" user "B.Adhesive")
		(13 "F.Paste" user "Package Geometry/Pastemask Top")
		(15 "B.Paste" user "Package Geometry/Pastemask Bottom")
		(5 "F.SilkS" user "Ref Des/Silkscreen Top")
		(7 "B.SilkS" user "Ref Des/Silkscreen Bottom")
		(1 "F.Mask" user "Board Geometry/Soldermask Top")
		(3 "B.Mask" user "Board Geometry/Soldermask Bottom")
		(17 "Dwgs.User" user "User.Drawings")
		(19 "Cmts.User" user "User.Comments")
		(21 "Eco1.User" user "User.Eco1")
		(23 "Eco2.User" user "User.Eco2")
		(25 "Edge.Cuts" user "Board Geometry/Outline")
		(27 "Margin" user)
		(31 "F.CrtYd" user "Package Geometry/Place Bound Top")
		(29 "B.CrtYd" user "Package Geometry/Place Bound Bottom")
		(35 "F.Fab" user "Ref Des/Assembly Top")
		(33 "B.Fab" user "Ref Des/Assembly Bottom")
	)
	(footprint ""
		(layer "B.Cu")
		(at 182.294276 -407.219912 90)
		(property "Reference" "R3909"
			(at 0 0 90)
			(layer "B.SilkS")
			(hide yes)
			(effects
				(font
					(size 1.27 1.27)
				)
				(justify mirror)
			)
		)
		(property "Value" ""
			(at 0 0 90)
			(layer "B.Fab")
			(effects
				(font
					(size 1.27 1.27)
				)
				(justify mirror)
			)
		)
		(duplicate_pad_numbers_are_jumpers no)
		(fp_line
			(start 0.7874 -0.4064)
			(end -0.7874 -0.4064)
			(stroke
				(width 0.1524)
				(type default)
			)
			(layer "B.SilkS")
		)
		(fp_line
			(start -0.7874 -0.4064)
			(end -0.7874 0.4064)
			(stroke
				(width 0.1524)
				(type default)
			)
			(layer "B.SilkS")
		)
		(fp_line
			(start 0.7874 0.4064)
			(end 0.7874 -0.4064)
			(stroke
				(width 0.1524)
				(type default)
			)
			(layer "B.SilkS")
		)
		(fp_line
			(start -0.7874 0.4064)
			(end 0.7874 0.4064)
			(stroke
				(width 0.1524)
				(type default)
			)
			(layer "B.SilkS")
		)
		(fp_line
			(start 0.67945 -0.305054)
			(end 0.12065 -0.305054)
			(stroke
				(width 0.1)
				(type default)
			)
			(layer "B.Fab")
		)
		(fp_line
			(start 0.12065 -0.305054)
			(end 0.12065 -0.2794)
			(stroke
				(width 0.1)
				(type default)
			)
			(layer "B.Fab")
		)
		(fp_line
			(start -0.12065 -0.3048)
			(end -0.67945 -0.3048)
			(stroke
				(width 0.1)
				(type default)
			)
			(layer "B.Fab")
		)
		(fp_line
			(start -0.67945 -0.3048)
			(end -0.67945 0.3048)
			(stroke
				(width 0.1)
				(type default)
			)
			(layer "B.Fab")
		)
		(fp_line
			(start 0.12065 -0.2794)
			(end -0.12065 -0.2794)
			(stroke
				(width 0.1)
				(type default)
			)
			(layer "B.Fab")
		)
		(fp_line
			(start -0.12065 -0.2794)
			(end -0.12065 -0.3048)
			(stroke
				(width 0.1)
				(type default)
			)
			(layer "B.Fab")
		)
		(fp_line
			(start 0.12065 0.2794)
			(end 0.12065 0.3048)
			(stroke
				(width 0.1)
				(type default)
			)
			(layer "B.Fab")
		)
		(fp_line
			(start -0.120396 0.2794)
			(end 0.12065 0.2794)
			(stroke
				(width 0.1)
				(type default)
			)
			(layer "B.Fab")
		)
		(fp_line
			(start 0.67945 0.3048)
			(end 0.67945 -0.305054)
			(stroke
				(width 0.1)
				(type default)
			)
			(layer "B.Fab")
		)
		(fp_line
			(start 0.12065 0.3048)
			(end 0.67945 0.3048)
			(stroke
				(width 0.1)
				(type default)
			)
			(layer "B.Fab")
		)
		(fp_line
			(start -0.120396 0.3048)
			(end -0.120396 0.2794)
			(stroke
				(width 0.1)
				(type default)
			)
			(layer "B.Fab")
		)
		(fp_line
			(start -0.67945 0.3048)
			(end -0.120396 0.3048)
			(stroke
				(width 0.1)
				(type default)
			)
			(layer "B.Fab")
		)
		(pad "1" smd circle
			(at 0.40005 0 270)
			(size 0 0)
			(layers "B.Cu" "B.Mask" "B.Paste")
			(net "SMB_SML1_PMBUS_HSC_SCL")
		)
		(pad "2" smd circle
			(at -0.40005 0 270)
			(size 0 0)
			(layers "B.Cu" "B.Mask" "B.Paste")
			(net "SMB_SML1_PMBUS_HSC_L_SCL")
		)
	)
	(footprint ""
		(layer "B.Cu")
		(at 111.800386 -246.066564 90)
		(property "Reference" "C2321"
			(at 0 0 90)
			(layer "B.SilkS")
			(hide yes)
			(effects
				(font
					(size 1.27 1.27)
				)
				(justify mirror)
			)
		)
		(property "Value" ""
			(at 0 0 90)
			(layer "B.Fab")
			(effects
				(font
					(size 1.27 1.27)
				)
				(justify mirror)
			)
		)
		(duplicate_pad_numbers_are_jumpers no)
		(fp_line
			(start 0.7874 -0.4064)
			(end -0.7874 -0.4064)
			(stroke
				(width 0.1524)
				(type default)
			)
			(layer "B.SilkS")
		)
		(fp_line
			(start -0.7874 -0.4064)
			(end -0.7874 0.4064)
			(stroke
				(width 0.1524)
				(type default)
			)
			(layer "B.SilkS")
		)
		(fp_line
			(start 0.7874 0.4064)
			(end 0.7874 -0.4064)
			(stroke
				(width 0.1524)
				(type default)
			)
			(layer "B.SilkS")
		)
		(fp_line
			(start -0.7874 0.4064)
			(end 0.7874 0.4064)
			(stroke
				(width 0.1524)
				(type default)
			)
			(layer "B.SilkS")
		)
		(fp_line
			(start 0.67945 -0.305054)
			(end 0.12065 -0.305054)
			(stroke
				(width 0.1)
				(type default)
			)
			(layer "B.Fab")
		)
		(fp_line
			(start 0.12065 -0.305054)
			(end 0.12065 -0.2794)
			(stroke
				(width 0.1)
				(type default)
			)
			(layer "B.Fab")
		)
		(fp_line
			(start -0.12065 -0.3048)
			(end -0.67945 -0.3048)
			(stroke
				(width 0.1)
				(type default)
			)
			(layer "B.Fab")
		)
		(fp_line
			(start -0.67945 -0.3048)
			(end -0.67945 0.3048)
			(stroke
				(width 0.1)
				(type default)
			)
			(layer "B.Fab")
		)
		(fp_line
			(start 0.12065 -0.2794)
			(end -0.12065 -0.2794)
			(stroke
				(width 0.1)
				(type default)
			)
			(layer "B.Fab")
		)
		(fp_line
			(start -0.12065 -0.2794)
			(end -0.12065 -0.3048)
			(stroke
				(width 0.1)
				(type default)
			)
			(layer "B.Fab")
		)
		(fp_line
			(start 0.12065 0.2794)
			(end 0.12065 0.3048)
			(stroke
				(width 0.1)
				(type default)
			)
			(layer "B.Fab")
		)
		(fp_line
			(start -0.120396 0.2794)
			(end 0.12065 0.2794)
			(stroke
				(width 0.1)
				(type default)
			)
			(layer "B.Fab")
		)
		(fp_line
			(start 0.67945 0.3048)
			(end 0.67945 -0.305054)
			(stroke
				(width 0.1)
				(type default)
			)
			(layer "B.Fab")
		)
		(fp_line
			(start 0.12065 0.3048)
			(end 0.67945 0.3048)
			(stroke
				(width 0.1)
				(type default)
			)
			(layer "B.Fab")
		)
		(fp_line
			(start -0.120396 0.3048)
			(end -0.120396 0.2794)
			(stroke
				(width 0.1)
				(type default)
			)
			(layer "B.Fab")
		)
		(fp_line
			(start -0.67945 0.3048)
			(end -0.120396 0.3048)
			(stroke
				(width 0.1)
				(type default)
			)
			(layer "B.Fab")
		)
		(pad "1" smd circle
			(at 0.40005 0 270)
			(size 0 0)
			(layers "B.Cu" "B.Mask" "B.Paste")
			(net "PVDDCR_CPU0_P1")
		)
		(pad "2" smd circle
			(at -0.40005 0 270)
			(size 0 0)
			(layers "B.Cu" "B.Mask" "B.Paste")
			(net "GND")
		)
	)
	(footprint ""
		(layer "B.Cu")
		(at 123.865386 -268.418564)
		(property "Reference" "C2364"
			(at 0 0 0)
			(layer "B.SilkS")
			(hide yes)
			(effects
				(font
					(size 1.27 1.27)
				)
				(justify mirror)
			)
		)
		(property "Value" ""
			(at 0 0 0)
			(layer "B.Fab")
			(effects
				(font
					(size 1.27 1.27)
				)
				(justify mirror)
			)
		)
		(duplicate_pad_numbers_are_jumpers no)
		(fp_line
			(start -0.7874 -0.4064)
			(end -0.7874 0.4064)
			(stroke
				(width 0.1524)
				(type default)
			)
			(layer "B.SilkS")
		)
		(fp_line
			(start -0.7874 0.4064)
			(end 0.7874 0.4064)
			(stroke
				(width 0.1524)
				(type default)
			)
			(layer "B.SilkS")
		)
		(fp_line
			(start 0.7874 -0.4064)
			(end -0.7874 -0.4064)
			(stroke
				(width 0.1524)
				(type default)
			)
			(layer "B.SilkS")
		)
		(fp_line
			(start 0.7874 0.4064)
			(end 0.7874 -0.4064)
			(stroke
				(width 0.1524)
				(type default)
			)
			(layer "B.SilkS")
		)
		(fp_line
			(start -0.67945 -0.3048)
			(end -0.67945 0.3048)
			(stroke
				(width 0.1)
				(type default)
			)
			(layer "B.Fab")
		)
		(fp_line
			(start -0.67945 0.3048)
			(end -0.120396 0.3048)
			(stroke
				(width 0.1)
				(type default)
			)
			(layer "B.Fab")
		)
		(fp_line
			(start -0.12065 -0.3048)
			(end -0.67945 -0.3048)
			(stroke
				(width 0.1)
				(type default)
			)
			(layer "B.Fab")
		)
		(fp_line
			(start -0.12065 -0.2794)
			(end -0.12065 -0.3048)
			(stroke
				(width 0.1)
				(type default)
			)
			(layer "B.Fab")
		)
		(fp_line
			(start -0.120396 0.2794)
			(end 0.12065 0.2794)
			(stroke
				(width 0.1)
				(type default)
			)
			(layer "B.Fab")
		)
		(fp_line
			(start -0.120396 0.3048)
			(end -0.120396 0.2794)
			(stroke
				(width 0.1)
				(type default)
			)
			(layer "B.Fab")
		)
		(fp_line
			(start 0.12065 -0.305054)
			(end 0.12065 -0.2794)
			(stroke
				(width 0.1)
				(type default)
			)
			(layer "B.Fab")
		)
		(fp_line
			(start 0.12065 -0.2794)
			(end -0.12065 -0.2794)
			(stroke
				(width 0.1)
				(type default)
			)
			(layer "B.Fab")
		)
		(fp_line
			(start 0.12065 0.2794)
			(end 0.12065 0.3048)
			(stroke
				(width 0.1)
				(type default)
			)
			(layer "B.Fab")
		)
		(fp_line
			(start 0.12065 0.3048)
			(end 0.67945 0.3048)
			(stroke
				(width 0.1)
				(type default)
			)
			(layer "B.Fab")
		)
		(fp_line
			(start 0.67945 -0.305054)
			(end 0.12065 -0.305054)
			(stroke
				(width 0.1)
				(type default)
			)
			(layer "B.Fab")
		)
		(fp_line
			(start 0.67945 0.3048)
			(end 0.67945 -0.305054)
			(stroke
				(width 0.1)
				(type default)
			)
			(layer "B.Fab")
		)
		(pad "1" smd circle
			(at 0.40005 0 180)
			(size 0 0)
			(layers "B.Cu" "B.Mask" "B.Paste")
			(net "PVDDCR_CPU1_P1")
		)
		(pad "2" smd circle
			(at -0.40005 0 180)
			(size 0 0)
			(layers "B.Cu" "B.Mask" "B.Paste")
			(net "GND")
		)
	)
	(footprint ""
		(layer "B.Cu")
		(at 404.568152 -354.439728 -90)
		(property "Reference" "R6127"
			(at 0 0 90)
			(layer "B.SilkS")
			(hide yes)
			(effects
				(font
					(size 1.27 1.27)
				)
				(justify mirror)
			)
		)
		(property "Value" ""
			(at 0 0 90)
			(layer "B.Fab")
			(effects
				(font
					(size 1.27 1.27)
				)
				(justify mirror)
			)
		)
		(duplicate_pad_numbers_are_jumpers no)
		(fp_line
			(start -0.7874 0.4064)
			(end 0.7874 0.4064)
			(stroke
				(width 0.1524)
				(type default)
			)
			(layer "B.SilkS")
		)
		(fp_line
			(start 0.7874 0.4064)
			(end 0.7874 -0.4064)
			(stroke
				(width 0.1524)
				(type default)
			)
			(layer "B.SilkS")
		)
		(fp_line
			(start -0.7874 -0.4064)
			(end -0.7874 0.4064)
			(stroke
				(width 0.1524)
				(type default)
			)
			(layer "B.SilkS")
		)
		(fp_line
			(start 0.7874 -0.4064)
			(end -0.7874 -0.4064)
			(stroke
				(width 0.1524)
				(type default)
			)
			(layer "B.SilkS")
		)
		(fp_line
			(start -0.67945 0.3048)
			(end -0.120396 0.3048)
			(stroke
				(width 0.1)
				(type default)
			)
			(layer "B.Fab")
		)
		(fp_line
			(start -0.120396 0.3048)
			(end -0.120396 0.2794)
			(stroke
				(width 0.1)
				(type default)
			)
			(layer "B.Fab")
		)
		(fp_line
			(start 0.12065 0.3048)
			(end 0.67945 0.3048)
			(stroke
				(width 0.1)
				(type default)
			)
			(layer "B.Fab")
		)
		(fp_line
			(start 0.67945 0.3048)
			(end 0.67945 -0.305054)
			(stroke
				(width 0.1)
				(type default)
			)
			(layer "B.Fab")
		)
		(fp_line
			(start -0.120396 0.2794)
			(end 0.12065 0.2794)
			(stroke
				(width 0.1)
				(type default)
			)
			(layer "B.Fab")
		)
		(fp_line
			(start 0.12065 0.2794)
			(end 0.12065 0.3048)
			(stroke
				(width 0.1)
				(type default)
			)
			(layer "B.Fab")
		)
		(fp_line
			(start -0.12065 -0.2794)
			(end -0.12065 -0.3048)
			(stroke
				(width 0.1)
				(type default)
			)
			(layer "B.Fab")
		)
		(fp_line
			(start 0.12065 -0.2794)
			(end -0.12065 -0.2794)
			(stroke
				(width 0.1)
				(type default)
			)
			(layer "B.Fab")
		)
		(fp_line
			(start -0.67945 -0.3048)
			(end -0.67945 0.3048)
			(stroke
				(width 0.1)
				(type default)
			)
			(layer "B.Fab")
		)
		(fp_line
			(start -0.12065 -0.3048)
			(end -0.67945 -0.3048)
			(stroke
				(width 0.1)
				(type default)
			)
			(layer "B.Fab")
		)
		(fp_line
			(start 0.12065 -0.305054)
			(end 0.12065 -0.2794)
			(stroke
				(width 0.1)
				(type default)
			)
			(layer "B.Fab")
		)
		(fp_line
			(start 0.67945 -0.305054)
			(end 0.12065 -0.305054)
			(stroke
				(width 0.1)
				(type default)
			)
			(layer "B.Fab")
		)
		(pad "1" smd circle
			(at 0.40005 0 90)
			(size 0 0)
			(layers "B.Cu" "B.Mask" "B.Paste")
			(net "FM_BOARD_SKU_ID2")
		)
		(pad "2" smd circle
			(at -0.40005 0 90)
			(size 0 0)
			(layers "B.Cu" "B.Mask" "B.Paste")
			(net "GND")
		)
	)
	(footprint ""
		(layer "B.Cu")
		(at 514.718808 7.526274 90)
		(property "Reference" "X8005"
			(at 0.93726 -1.53035 270)
			(unlocked yes)
			(layer "B.SilkS")
			(effects
				(font
					(size 0.7874 0.5842)
					(thickness 0.1524)
				)
				(justify left mirror)
			)
		)
		(property "Value" ""
			(at 0 0 90)
			(layer "B.Fab")
			(effects
				(font
					(size 1.27 1.27)
				)
				(justify mirror)
			)
		)
		(property "Device Type" "TP_TDR_4P_FTS_TH-TP_TDR_4P_DIP,EMPTY,TP15"
			(at -1.30175 1.27 0)
			(unlocked yes)
			(layer "B.Fab")
			(hide yes)
			(effects
				(font
					(size 0.635 0.4064)
					(thickness 0.1524)
				)
				(justify mirror)
			)
		)
		(property "User Part Number" "N_A"
			(at -1.30175 1.27 0)
			(unlocked yes)
			(layer "Cmts.User")
			(hide yes)
			(effects
				(font
					(size 0.635 0.4064)
					(thickness 0.1524)
				)
				(justify mirror)
			)
		)
		(duplicate_pad_numbers_are_jumpers no)
		(fp_line
			(start 0 -1.27)
			(end 0 -0.635)
			(stroke
				(width 0.1524)
				(type default)
			)
			(layer "B.SilkS")
		)
		(fp_line
			(start -2.54 -1.27)
			(end 0 -1.27)
			(stroke
				(width 0.1524)
				(type default)
			)
			(layer "B.SilkS")
		)
		(fp_line
			(start -2.54 -1.1303)
			(end -2.54 -1.27)
			(stroke
				(width 0.1524)
				(type default)
			)
			(layer "B.SilkS")
		)
		(fp_line
			(start 0 0.635)
			(end 0 1.905)
			(stroke
				(width 0.1524)
				(type default)
			)
			(layer "B.SilkS")
		)
		(fp_line
			(start -2.54 1.4097)
			(end -2.54 1.1303)
			(stroke
				(width 0.1524)
				(type default)
			)
			(layer "B.SilkS")
		)
		(fp_line
			(start 0 3.175)
			(end 0 3.81)
			(stroke
				(width 0.1524)
				(type default)
			)
			(layer "B.SilkS")
		)
		(fp_line
			(start 0 3.81)
			(end -2.54 3.81)
			(stroke
				(width 0.1524)
				(type default)
			)
			(layer "B.SilkS")
		)
		(fp_line
			(start -2.54 3.81)
			(end -2.54 3.6703)
			(stroke
				(width 0.1524)
				(type default)
			)
			(layer "B.SilkS")
		)
		(fp_poly
			(pts
				(xy 0.761746 0) (xy 2.285746 -0.762) (xy 2.285746 0.762)
			)
			(stroke
				(width 0)
				(type default)
			)
			(fill yes)
			(layer "B.SilkS")
		)
		(fp_line
			(start 0 -1.27)
			(end 0 3.81)
			(stroke
				(width 0.1)
				(type default)
			)
			(layer "B.Fab")
		)
		(fp_line
			(start -2.54 -1.27)
			(end 0 -1.27)
			(stroke
				(width 0.1)
				(type default)
			)
			(layer "B.Fab")
		)
		(fp_line
			(start 0 3.81)
			(end -2.54 3.81)
			(stroke
				(width 0.1)
				(type default)
			)
			(layer "B.Fab")
		)
		(fp_line
			(start -2.54 3.81)
			(end -2.54 -1.27)
			(stroke
				(width 0.1)
				(type default)
			)
			(layer "B.Fab")
		)
		(fp_poly
			(pts
				(xy 0.761746 0) (xy 2.285746 -0.762) (xy 2.285746 0.762)
			)
			(stroke
				(width 0)
				(type default)
			)
			(fill yes)
			(layer "B.Fab")
		)
		(pad "1" thru_hole circle
			(at 0 0 270)
			(size 1.0033 1.0033)
			(drill 0.249936)
			(layers "*.Cu" "*.Mask")
			(remove_unused_layers no)
			(net "TDR_DIFF_85_IN4_DP")
			(clearance 0.10795)
			(padstack
				(mode front_inner_back)
				(layer "Inner"
					(shape circle)
					(size 0.8001 0.8001)
					(clearance 0.1524)
				)
				(layer "B.Cu"
					(shape circle)
					(size 1.0033 1.0033)
					(thermal_gap 0.10795)
					(clearance 0.10795)
				)
			)
		)
		(pad "2" thru_hole circle
			(at -2.54 0 270)
			(size 1.9939 1.9939)
			(drill 0.249936)
			(layers "*.Cu" "*.Mask")
			(remove_unused_layers no)
			(net "T1_GND")
			(clearance 0.10795)
			(padstack
				(mode front_inner_back)
				(layer "Inner"
					(shape circle)
					(size 0.8001 0.8001)
					(clearance 0.1524)
				)
				(layer "B.Cu"
					(shape circle)
					(size 1.9939 1.9939)
					(thermal_gap 0.10795)
					(clearance 0.10795)
				)
			)
		)
		(pad "3" thru_hole circle
			(at -2.54 2.54 270)
			(size 1.9939 1.9939)
			(drill 0.249936)
			(layers "*.Cu" "*.Mask")
			(remove_unused_layers no)
			(net "T1_GND")
			(clearance 0.10795)
			(padstack
				(mode front_inner_back)
				(layer "Inner"
					(shape circle)
					(size 0.8001 0.8001)
					(clearance 0.1524)
				)
				(layer "B.Cu"
					(shape circle)
					(size 1.9939 1.9939)
					(thermal_gap 0.10795)
					(clearance 0.10795)
				)
			)
		)
		(pad "4" thru_hole circle
			(at 0 2.54 270)
			(size 1.0033 1.0033)
			(drill 0.249936)
			(layers "*.Cu" "*.Mask")
			(remove_unused_layers no)
			(net "TDR_DIFF_85_IN4_DN")
			(clearance 0.10795)
			(padstack
				(mode front_inner_back)
				(layer "Inner"
					(shape circle)
					(size 0.8001 0.8001)
					(clearance 0.1524)
				)
				(layer "B.Cu"
					(shape circle)
					(size 1.0033 1.0033)
					(thermal_gap 0.10795)
					(clearance 0.10795)
				)
			)
		)
	)
	(footprint ""
		(layer "B.Cu")
		(at 385.3942 -191.33058 90)
		(property "Reference" "PC565_4"
			(at 0 0 90)
			(layer "B.SilkS")
			(hide yes)
			(effects
				(font
					(size 1.27 1.27)
				)
				(justify mirror)
			)
		)
		(property "Value" ""
			(at 0 0 90)
			(layer "B.Fab")
			(effects
				(font
					(size 1.27 1.27)
				)
				(justify mirror)
			)
		)
		(duplicate_pad_numbers_are_jumpers no)
		(fp_line
			(start 1.524 -0.762)
			(end -1.524 -0.762)
			(stroke
				(width 0.1524)
				(type default)
			)
			(layer "B.SilkS")
		)
		(fp_line
			(start -1.524 -0.762)
			(end -1.524 0.762)
			(stroke
				(width 0.1524)
				(type default)
			)
			(layer "B.SilkS")
		)
		(fp_line
			(start 1.524 0.762)
			(end 1.524 -0.762)
			(stroke
				(width 0.1524)
				(type default)
			)
			(layer "B.SilkS")
		)
		(fp_line
			(start -1.524 0.762)
			(end 1.524 0.762)
			(stroke
				(width 0.1524)
				(type default)
			)
			(layer "B.SilkS")
		)
		(fp_line
			(start 1.1049 -0.724916)
			(end 1.1049 0.724916)
			(stroke
				(width 0.1)
				(type default)
			)
			(layer "B.Fab")
		)
		(fp_line
			(start -1.1049 -0.724916)
			(end 1.1049 -0.724916)
			(stroke
				(width 0.1)
				(type default)
			)
			(layer "B.Fab")
		)
		(fp_line
			(start 1.1049 0.724916)
			(end -1.1049 0.724916)
			(stroke
				(width 0.1)
				(type default)
			)
			(layer "B.Fab")
		)
		(fp_line
			(start -1.1049 0.724916)
			(end -1.1049 -0.724916)
			(stroke
				(width 0.1)
				(type default)
			)
			(layer "B.Fab")
		)
		(pad "1" smd rect
			(at 0.889 0 90)
			(size 1.016 1.27)
			(layers "B.Cu" "B.Mask" "B.Paste")
			(net "PVDDCR_CPU0_P0")
		)
		(pad "2" smd rect
			(at -0.889 0 90)
			(size 1.016 1.27)
			(layers "B.Cu" "B.Mask" "B.Paste")
			(net "GND")
		)
	)
)
